# TIMECARD (Time Appliance Project (Time Card)) — schematic netlist excerpt (pin names and nets, part order shuffled) for the footprints in the layout excerpt that follows; sources: Cadence DE-HDL packaged netlist, KiCad conversion of R4006-B0001-02_R01.brd

U4  PCA9546APW_TSSOP16  pkg SOP16_173_P0256_H043  page 16
  A0  = UNNAMED_5_PCA9546APWTSSOP16_I33
  A1  = UNNAMED_5_PCA9546APWTSSOP16_I_1
  \reset*\  = PCA9546_RST_N
  SD0  = LM75B_I2C_SDA
  SC0  = LM75B_I2C_SCL
  SD1  = SHT3X_I2C_SDA
  SC1  = SHT3X_I2C_SCL
  VSS  = SG
  SD2  = ICP10100_I2C_SDA
  SC2  = ICP10100_I2C_SCL
  SD3  = BNO080_I2C_SDA
  SC3  = BNO080_I2C_SCL
  A2  = UNNAMED_5_PCA9546APWTSSOP16_I_2
  SCL  = R_PCA9546_I2C_SCL
  SDA  = R_PCA9546_I2C_SDA
  VDD  = VDD_PCA9546A

(kicad_pcb
	(version 20260206)
	(generator "pcbnew")
	(generator_version "10.0")
	(general
		(thickness 1.6)
		(legacy_teardrops no)
	)
	(paper "A4")
	(title_block
		(title "timecard-production-celestica-r4006 — R4006-B0001-02_R01.brd")
		(comment 1 "Time Appliance Project (Time Card) / footprints 67-67 of 1113")
	)
	(layers
		(0 "F.Cu" signal "TOP")
		(4 "In1.Cu" signal "L02_GND1")
		(6 "In2.Cu" signal "L03_SIG1")
		(8 "In3.Cu" signal "L04_GND2")
		(10 "In4.Cu" signal "L05_VCC1")
		(12 "In5.Cu" signal "L06_VCC2")
		(14 "In6.Cu" signal "L07_GND3")
		(16 "In7.Cu" signal "L08_SIG2")
		(18 "In8.Cu" signal "L09_GND4")
		(2 "B.Cu" signal "BOTTOM")
		(9 "F.Adhes" user "F.Adhesive")
		(11 "B.Adhes" user "B.Adhesive")
		(13 "F.Paste" user "Package Geometry/Pastemask Top")
		(15 "B.Paste" user "Package Geometry/Pastemask Bottom")
		(5 "F.SilkS" user "Ref Des/Silkscreen Top")
		(7 "B.SilkS" user "Ref Des/Silkscreen Bottom")
		(1 "F.Mask" user "Board Geometry/Soldermask Top")
		(3 "B.Mask" user "Board Geometry/Soldermask Bottom")
		(17 "Dwgs.User" user "User.Drawings")
		(19 "Cmts.User" user "User.Comments")
		(21 "Eco1.User" user "User.Eco1")
		(23 "Eco2.User" user "User.Eco2")
		(25 "Edge.Cuts" user "Board Geometry/Outline")
		(27 "Margin" user)
		(31 "F.CrtYd" user "Package Geometry/Place Bound Top")
		(29 "B.CrtYd" user "Package Geometry/Place Bound Bottom")
		(35 "F.Fab" user "Ref Des/Assembly Top")
		(33 "B.Fab" user "Ref Des/Assembly Bottom")
	)
	(footprint ""
		(layer "F.Cu")
		(at 80.3148 -84.201 180)
		(property "Reference" "U4"
			(at 0.3048 3.52933 0)
			(unlocked yes)
			(layer "F.SilkS")
			(effects
				(font
					(size 0.7874 0.5842)
					(thickness 0.1524)
				)
			)
		)
		(property "Value" ""
			(at 0 0 180)
			(layer "F.Fab")
			(effects
				(font
					(size 1.27 1.27)
				)
			)
		)
		(property "Device Type" "PCA9546APW_TSSOP16-G223-10280-A"
			(at 0 0.924306 180)
			(unlocked yes)
			(layer "F.Fab")
			(hide yes)
			(effects
				(font
					(size 0.7874 0.5842)
					(thickness 0.1524)
				)
			)
		)
		(property "User Part Number" "PARTNUM*"
			(at 0 1.940306 180)
			(unlocked yes)
			(layer "Cmts.User")
			(hide yes)
			(effects
				(font
					(size 0.7874 0.5842)
					(thickness 0.1524)
				)
			)
		)
		(duplicate_pad_numbers_are_jumpers no)
		(fp_line
			(start 4.0767 2.7559)
			(end -4.0767 2.7559)
			(stroke
				(width 0.1)
				(type default)
			)
			(layer "F.SilkS")
		)
		(fp_line
			(start 4.0767 -2.7559)
			(end 4.0767 2.7559)
			(stroke
				(width 0.1)
				(type default)
			)
			(layer "F.SilkS")
		)
		(fp_line
			(start -4.0767 2.7559)
			(end -4.0767 -2.7559)
			(stroke
				(width 0.1)
				(type default)
			)
			(layer "F.SilkS")
		)
		(fp_line
			(start -4.0767 -2.7559)
			(end 4.0767 -2.7559)
			(stroke
				(width 0.1)
				(type default)
			)
			(layer "F.SilkS")
		)
		(fp_poly
			(pts
				(arc
					(start -5.1435 -2.2225)
					(mid -4.3815 -2.2225)
					(end -5.1435 -2.2225)
				)
			)
			(stroke
				(width 0)
				(type default)
			)
			(fill yes)
			(layer "F.SilkS")
		)
		(fp_rect
			(start -4.3307 3.0099)
			(end 4.3307 -3.0099)
			(stroke
				(width 0)
				(type default)
			)
			(fill no)
			(layer "F.CrtYd")
		)
		(fp_line
			(start 2.1971 2.5019)
			(end -2.1971 2.5019)
			(stroke
				(width 0.1)
				(type default)
			)
			(layer "F.Fab")
		)
		(fp_line
			(start 2.1971 -2.5019)
			(end 2.1971 2.5019)
			(stroke
				(width 0.1)
				(type default)
			)
			(layer "F.Fab")
		)
		(fp_line
			(start -2.1971 2.5019)
			(end -2.1971 -2.5019)
			(stroke
				(width 0.1)
				(type default)
			)
			(layer "F.Fab")
		)
		(fp_line
			(start -2.1971 -2.5019)
			(end 2.1971 -2.5019)
			(stroke
				(width 0.1)
				(type default)
			)
			(layer "F.Fab")
		)
		(fp_poly
			(pts
				(arc
					(start -1.914652 -1.942084)
					(mid -1.114044 -1.941576)
					(end -1.914652 -1.942084)
				)
			)
			(stroke
				(width 0)
				(type default)
			)
			(fill yes)
			(layer "F.Fab")
		)
		(fp_text user "9"
			(at 4.5466 2.31267 180)
			(unlocked yes)
			(layer "F.SilkS")
			(effects
				(font
					(size 0.7874 0.5842)
					(thickness 0.1524)
				)
			)
		)
		(fp_text user "16"
			(at 2.8448 -3.72237 0)
			(unlocked yes)
			(layer "F.SilkS")
			(effects
				(font
					(size 0.7874 0.5842)
					(thickness 0.1524)
				)
			)
		)
		(fp_text user "8"
			(at -4.6482 2.11963 0)
			(unlocked yes)
			(layer "F.SilkS")
			(effects
				(font
					(size 0.7874 0.5842)
					(thickness 0.1524)
				)
			)
		)
		(fp_text user "16"
			(at 3.0988 -2.43967 0)
			(unlocked yes)
			(layer "F.Fab")
			(effects
				(font
					(size 0.7874 0.5842)
					(thickness 0.1524)
				)
			)
		)
		(fp_text user "9"
			(at 2.9718 2.25933 0)
			(unlocked yes)
			(layer "F.Fab")
			(effects
				(font
					(size 0.7874 0.5842)
					(thickness 0.1524)
				)
			)
		)
		(fp_text user "8"
			(at -2.7432 2.38633 0)
			(unlocked yes)
			(layer "F.Fab")
			(effects
				(font
					(size 0.7874 0.5842)
					(thickness 0.1524)
				)
			)
		)
		(pad "1" smd rect
			(at -3.0353 -2.275078 270)
			(size 0.3556 1.5748)
			(layers "F.Cu" "F.Mask" "F.Paste")
			(net "UNNAMED_5_PCA9546APWTSSOP16_I33")
		)
		(pad "2" smd rect
			(at -3.0353 -1.625092 270)
			(size 0.3556 1.5748)
			(layers "F.Cu" "F.Mask" "F.Paste")
			(net "UNNAMED_5_PCA9546APWTSSOP16_I_1")
		)
		(pad "3" smd rect
			(at -3.0353 -0.975106 270)
			(size 0.3556 1.5748)
			(layers "F.Cu" "F.Mask" "F.Paste")
			(net "PCA9546_RST_N")
		)
		(pad "4" smd rect
			(at -3.0353 -0.32512 270)
			(size 0.3556 1.5748)
			(layers "F.Cu" "F.Mask" "F.Paste")
			(net "LM75B_I2C_SDA")
		)
		(pad "5" smd rect
			(at -3.0353 0.32512 270)
			(size 0.3556 1.5748)
			(layers "F.Cu" "F.Mask" "F.Paste")
			(net "LM75B_I2C_SCL")
		)
		(pad "6" smd rect
			(at -3.0353 0.975106 270)
			(size 0.3556 1.5748)
			(layers "F.Cu" "F.Mask" "F.Paste")
			(net "SHT3X_I2C_SDA")
		)
		(pad "7" smd rect
			(at -3.0353 1.625092 270)
			(size 0.3556 1.5748)
			(layers "F.Cu" "F.Mask" "F.Paste")
			(net "SHT3X_I2C_SCL")
		)
		(pad "8" smd rect
			(at -3.0353 2.275078 270)
			(size 0.3556 1.5748)
			(layers "F.Cu" "F.Mask" "F.Paste")
			(net "SG")
		)
		(pad "9" smd rect
			(at 3.0353 2.275078 270)
			(size 0.3556 1.5748)
			(layers "F.Cu" "F.Mask" "F.Paste")
			(net "ICP10100_I2C_SDA")
		)
		(pad "10" smd rect
			(at 3.0353 1.625092 270)
			(size 0.3556 1.5748)
			(layers "F.Cu" "F.Mask" "F.Paste")
			(net "ICP10100_I2C_SCL")
		)
		(pad "11" smd rect
			(at 3.0353 0.975106 270)
			(size 0.3556 1.5748)
			(layers "F.Cu" "F.Mask" "F.Paste")
			(net "BNO080_I2C_SDA")
		)
		(pad "12" smd rect
			(at 3.0353 0.32512 270)
			(size 0.3556 1.5748)
			(layers "F.Cu" "F.Mask" "F.Paste")
			(net "BNO080_I2C_SCL")
		)
		(pad "13" smd rect
			(at 3.0353 -0.32512 270)
			(size 0.3556 1.5748)
			(layers "F.Cu" "F.Mask" "F.Paste")
			(net "UNNAMED_5_PCA9546APWTSSOP16_I_2")
		)
		(pad "14" smd rect
			(at 3.0353 -0.975106 270)
			(size 0.3556 1.5748)
			(layers "F.Cu" "F.Mask" "F.Paste")
			(net "R_PCA9546_I2C_SCL")
		)
		(pad "15" smd rect
			(at 3.0353 -1.625092 270)
			(size 0.3556 1.5748)
			(layers "F.Cu" "F.Mask" "F.Paste")
			(net "R_PCA9546_I2C_SDA")
		)
		(pad "16" smd rect
			(at 3.0353 -2.275078 270)
			(size 0.3556 1.5748)
			(layers "F.Cu" "F.Mask" "F.Paste")
			(net "VDD_PCA9546A")
		)
	)
)
